(kicad_pcb
	(version 20260206)
	(generator "pcbnew")
	(generator_version "10.0")
	(general
		(thickness 1.6)
		(legacy_teardrops no)
	)
	(paper "A4")
	(title_block
		(title "baseboard — 13948-1b.1110WZS1818.brd")
		(comment 1 "Honey Badger (Wiwynn) / footprint 1425 of 2523 (MEZCN1), pads 1-120 of 122")
	)
	(layers
		(0 "F.Cu" signal "TOP")
		(4 "In1.Cu" signal "L2GND")
		(6 "In2.Cu" signal "L3")
		(8 "In3.Cu" signal "L4VCC")
		(10 "In4.Cu" signal "L5VCC")
		(12 "In5.Cu" signal "L6")
		(14 "In6.Cu" signal "L7GND")
		(2 "B.Cu" signal "BOTTOM")
		(9 "F.Adhes" user "F.Adhesive")
		(11 "B.Adhes" user "B.Adhesive")
		(13 "F.Paste" user "Package Geometry/Pastemask Top")
		(15 "B.Paste" user "Package Geometry/Pastemask Bottom")
		(5 "F.SilkS" user "Ref Des/Silkscreen Top")
		(7 "B.SilkS" user "Ref Des/Silkscreen Bottom")
		(1 "F.Mask" user "Board Geometry/Soldermask Top")
		(3 "B.Mask" user "Board Geometry/Soldermask Bottom")
		(17 "Dwgs.User" user "User.Drawings")
		(19 "Cmts.User" user "User.Comments")
		(21 "Eco1.User" user "User.Eco1")
		(23 "Eco2.User" user "User.Eco2")
		(25 "Edge.Cuts" user "Board Geometry/Outline")
		(27 "Margin" user)
		(31 "F.CrtYd" user "Package Geometry/Place Bound Top")
		(29 "B.CrtYd" user "Package Geometry/Place Bound Bottom")
		(35 "F.Fab" user "Ref Des/Assembly Top")
		(33 "B.Fab" user "Ref Des/Assembly Bottom")
	)
	(footprint ""
		(layer "F.Cu")
		(at 310.900064 -72.00011 -90)
		(property "Reference" "MEZCN1"
			(at 0 0 270)
			(layer "F.SilkS")
			(hide yes)
			(effects
				(font
					(size 1.27 1.27)
				)
			)
		)
		(property "Value" "FCI-CONN120-GP"
			(at -29.345382 -6.235192 270)
			(unlocked yes)
			(layer "F.Fab")
			(hide yes)
			(effects
				(font
					(size 1.016 1.016)
					(thickness 0.1524)
				)
			)
		)
		(property "Device Type" "61082-121402LF-U"
			(at -29.345382 -7.759192 270)
			(unlocked yes)
			(layer "F.Fab")
			(hide yes)
			(effects
				(font
					(size 1.016 1.016)
					(thickness 0.1524)
				)
			)
		)
		(duplicate_pad_numbers_are_jumpers no)
		(pad "" np_thru_hole circle
			(at -26.100024 0 270)
			(size 0.254 0.254)
			(drill 0.8636)
			(layers "*.Cu" "*.Mask")
			(clearance 0.6604)
			(thermal_gap 0.6604)
		)
		(pad "" np_thru_hole circle
			(at 26.100024 0 270)
			(size 0.254 0.254)
			(drill 1.2192)
			(layers "*.Cu" "*.Mask")
			(clearance 0.8382)
			(thermal_gap 0.8382)
		)
		(pad "1" smd rect
			(at 23.599902 -2.22504 270)
			(size 0.508 2.0574)
			(layers "F.Cu" "F.Mask" "F.Paste")
			(net "CONN_10G_PRSNT2_N")
		)
		(pad "2" smd rect
			(at 22.800056 -2.22504 270)
			(size 0.508 2.0574)
			(layers "F.Cu" "F.Mask" "F.Paste")
			(net "P5V_STBY")
		)
		(pad "3" smd rect
			(at 21.999956 -2.22504 270)
			(size 0.508 2.0574)
			(layers "F.Cu" "F.Mask" "F.Paste")
			(net "P5V_STBY")
		)
		(pad "4" smd rect
			(at 21.20011 -2.22504 270)
			(size 0.508 2.0574)
			(layers "F.Cu" "F.Mask" "F.Paste")
			(net "P5V_STBY")
		)
		(pad "5" smd rect
			(at 20.40001 -2.22504 270)
			(size 0.508 2.0574)
			(layers "F.Cu" "F.Mask" "F.Paste")
			(net "GND")
		)
		(pad "6" smd rect
			(at 19.59991 -2.22504 270)
			(size 0.508 2.0574)
			(layers "F.Cu" "F.Mask" "F.Paste")
			(net "GND")
		)
		(pad "7" smd rect
			(at 18.800064 -2.22504 270)
			(size 0.508 2.0574)
			(layers "F.Cu" "F.Mask" "F.Paste")
			(net "P3V3_STBY")
		)
		(pad "8" smd rect
			(at 17.999964 -2.22504 270)
			(size 0.508 2.0574)
			(layers "F.Cu" "F.Mask" "F.Paste")
			(net "GND")
		)
		(pad "9" smd rect
			(at 17.200118 -2.22504 270)
			(size 0.508 2.0574)
			(layers "F.Cu" "F.Mask" "F.Paste")
			(net "GND")
		)
		(pad "10" smd rect
			(at 16.400018 -2.22504 270)
			(size 0.508 2.0574)
			(layers "F.Cu" "F.Mask" "F.Paste")
			(net "P3V3")
		)
		(pad "11" smd rect
			(at 15.599918 -2.22504 270)
			(size 0.508 2.0574)
			(layers "F.Cu" "F.Mask" "F.Paste")
			(net "P3V3")
		)
		(pad "12" smd rect
			(at 14.800072 -2.22504 270)
			(size 0.508 2.0574)
			(layers "F.Cu" "F.Mask" "F.Paste")
			(net "P3V3")
		)
		(pad "13" smd rect
			(at 13.999972 -2.22504 270)
			(size 0.508 2.0574)
			(layers "F.Cu" "F.Mask" "F.Paste")
			(net "P3V3")
		)
		(pad "14" smd rect
			(at 13.200126 -2.22504 270)
			(size 0.508 2.0574)
			(layers "F.Cu" "F.Mask" "F.Paste")
			(net "NCSI_10G_RCSDV_R")
		)
		(pad "15" smd rect
			(at 12.400026 -2.22504 270)
			(size 0.508 2.0574)
			(layers "F.Cu" "F.Mask" "F.Paste")
			(net "NCSI_10G_RCLK_R")
		)
		(pad "16" smd rect
			(at 11.599926 -2.22504 270)
			(size 0.508 2.0574)
			(layers "F.Cu" "F.Mask" "F.Paste")
			(net "NCSI_10G_TXEN_R")
		)
		(pad "17" smd rect
			(at 10.80008 -2.22504 270)
			(size 0.508 2.0574)
			(layers "F.Cu" "F.Mask" "F.Paste")
			(net "PMU_PLTRST_N_10G")
		)
		(pad "18" smd rect
			(at 9.99998 -2.22504 270)
			(size 0.508 2.0574)
			(layers "F.Cu" "F.Mask" "F.Paste")
			(net "I2C_BMC_MSB_CLK_R")
		)
		(pad "19" smd rect
			(at 9.19988 -2.22504 270)
			(size 0.508 2.0574)
			(layers "F.Cu" "F.Mask" "F.Paste")
			(net "I2C_BMC_MSB_DATA_R")
		)
		(pad "20" smd rect
			(at 8.400034 -2.22504 270)
			(size 0.508 2.0574)
			(layers "F.Cu" "F.Mask" "F.Paste")
			(net "GND")
		)
		(pad "21" smd rect
			(at 7.599934 -2.22504 270)
			(size 0.508 2.0574)
			(layers "F.Cu" "F.Mask" "F.Paste")
			(net "GND")
		)
		(pad "22" smd rect
			(at 6.800088 -2.22504 270)
			(size 0.508 2.0574)
			(layers "F.Cu" "F.Mask" "F.Paste")
			(net "NCSI_10G_RXD0_R")
		)
		(pad "23" smd rect
			(at 5.999988 -2.22504 270)
			(size 0.508 2.0574)
			(layers "F.Cu" "F.Mask" "F.Paste")
			(net "NCSI_10G_RXD1_R")
		)
		(pad "24" smd rect
			(at 5.199888 -2.22504 270)
			(size 0.508 2.0574)
			(layers "F.Cu" "F.Mask" "F.Paste")
			(net "GND")
		)
		(pad "25" smd rect
			(at 4.400042 -2.22504 270)
			(size 0.508 2.0574)
			(layers "F.Cu" "F.Mask" "F.Paste")
			(net "GND")
		)
		(pad "26" smd rect
			(at 3.599942 -2.22504 270)
			(size 0.508 2.0574)
			(layers "F.Cu" "F.Mask" "F.Paste")
			(net "PCIE_10G_REFCLK_2_P")
		)
		(pad "27" smd rect
			(at 2.800096 -2.22504 270)
			(size 0.508 2.0574)
			(layers "F.Cu" "F.Mask" "F.Paste")
			(net "PCIE_10G_REFCLK_2_N")
		)
		(pad "28" smd rect
			(at 1.999996 -2.22504 270)
			(size 0.508 2.0574)
			(layers "F.Cu" "F.Mask" "F.Paste")
			(net "GND")
		)
		(pad "29" smd rect
			(at 1.199896 -2.22504 270)
			(size 0.508 2.0574)
			(layers "F.Cu" "F.Mask" "F.Paste")
			(net "GND")
		)
		(pad "30" smd rect
			(at 0.40005 -2.22504 270)
			(size 0.508 2.0574)
			(layers "F.Cu" "F.Mask" "F.Paste")
			(net "PCIE_10G_CPU_RX0_P")
		)
		(pad "31" smd rect
			(at -0.40005 -2.22504 270)
			(size 0.508 2.0574)
			(layers "F.Cu" "F.Mask" "F.Paste")
			(net "PCIE_10G_CPU_RX0_N")
		)
		(pad "32" smd rect
			(at -1.199896 -2.22504 270)
			(size 0.508 2.0574)
			(layers "F.Cu" "F.Mask" "F.Paste")
			(net "GND")
		)
		(pad "33" smd rect
			(at -1.999996 -2.22504 270)
			(size 0.508 2.0574)
			(layers "F.Cu" "F.Mask" "F.Paste")
			(net "GND")
		)
		(pad "34" smd rect
			(at -2.800096 -2.22504 270)
			(size 0.508 2.0574)
			(layers "F.Cu" "F.Mask" "F.Paste")
			(net "PCIE_10G_CPU_RX1_P")
		)
		(pad "35" smd rect
			(at -3.599942 -2.22504 270)
			(size 0.508 2.0574)
			(layers "F.Cu" "F.Mask" "F.Paste")
			(net "PCIE_10G_CPU_RX1_N")
		)
		(pad "36" smd rect
			(at -4.400042 -2.22504 270)
			(size 0.508 2.0574)
			(layers "F.Cu" "F.Mask" "F.Paste")
			(net "GND")
		)
		(pad "37" smd rect
			(at -5.199888 -2.22504 270)
			(size 0.508 2.0574)
			(layers "F.Cu" "F.Mask" "F.Paste")
			(net "GND")
		)
		(pad "38" smd rect
			(at -5.999988 -2.22504 270)
			(size 0.508 2.0574)
			(layers "F.Cu" "F.Mask" "F.Paste")
			(net "PCIE_10G_CPU_RX2_P")
		)
		(pad "39" smd rect
			(at -6.800088 -2.22504 270)
			(size 0.508 2.0574)
			(layers "F.Cu" "F.Mask" "F.Paste")
			(net "PCIE_10G_CPU_RX2_N")
		)
		(pad "40" smd rect
			(at -7.599934 -2.22504 270)
			(size 0.508 2.0574)
			(layers "F.Cu" "F.Mask" "F.Paste")
			(net "GND")
		)
		(pad "41" smd rect
			(at -8.400034 -2.22504 270)
			(size 0.508 2.0574)
			(layers "F.Cu" "F.Mask" "F.Paste")
			(net "GND")
		)
		(pad "42" smd rect
			(at -9.19988 -2.22504 270)
			(size 0.508 2.0574)
			(layers "F.Cu" "F.Mask" "F.Paste")
			(net "PCIE_10G_CPU_RX3_P")
		)
		(pad "43" smd rect
			(at -9.99998 -2.22504 270)
			(size 0.508 2.0574)
			(layers "F.Cu" "F.Mask" "F.Paste")
			(net "PCIE_10G_CPU_RX3_N")
		)
		(pad "44" smd rect
			(at -10.80008 -2.22504 270)
			(size 0.508 2.0574)
			(layers "F.Cu" "F.Mask" "F.Paste")
			(net "GND")
		)
		(pad "45" smd rect
			(at -11.599926 -2.22504 270)
			(size 0.508 2.0574)
			(layers "F.Cu" "F.Mask" "F.Paste")
			(net "GND")
		)
		(pad "46" smd rect
			(at -12.400026 -2.22504 270)
			(size 0.508 2.0574)
			(layers "F.Cu" "F.Mask" "F.Paste")
			(net "Net_1326")
		)
		(pad "47" smd rect
			(at -13.200126 -2.22504 270)
			(size 0.508 2.0574)
			(layers "F.Cu" "F.Mask" "F.Paste")
			(net "Net_1325")
		)
		(pad "48" smd rect
			(at -13.999972 -2.22504 270)
			(size 0.508 2.0574)
			(layers "F.Cu" "F.Mask" "F.Paste")
			(net "GND")
		)
		(pad "49" smd rect
			(at -14.800072 -2.22504 270)
			(size 0.508 2.0574)
			(layers "F.Cu" "F.Mask" "F.Paste")
			(net "GND")
		)
		(pad "50" smd rect
			(at -15.599918 -2.22504 270)
			(size 0.508 2.0574)
			(layers "F.Cu" "F.Mask" "F.Paste")
			(net "Net_1324")
		)
		(pad "51" smd rect
			(at -16.400018 -2.22504 270)
			(size 0.508 2.0574)
			(layers "F.Cu" "F.Mask" "F.Paste")
			(net "Net_1323")
		)
		(pad "52" smd rect
			(at -17.200118 -2.22504 270)
			(size 0.508 2.0574)
			(layers "F.Cu" "F.Mask" "F.Paste")
			(net "GND")
		)
		(pad "53" smd rect
			(at -17.999964 -2.22504 270)
			(size 0.508 2.0574)
			(layers "F.Cu" "F.Mask" "F.Paste")
			(net "GND")
		)
		(pad "54" smd rect
			(at -18.800064 -2.22504 270)
			(size 0.508 2.0574)
			(layers "F.Cu" "F.Mask" "F.Paste")
			(net "Net_1322")
		)
		(pad "55" smd rect
			(at -19.59991 -2.22504 270)
			(size 0.508 2.0574)
			(layers "F.Cu" "F.Mask" "F.Paste")
			(net "Net_1331")
		)
		(pad "56" smd rect
			(at -20.40001 -2.22504 270)
			(size 0.508 2.0574)
			(layers "F.Cu" "F.Mask" "F.Paste")
			(net "GND")
		)
		(pad "57" smd rect
			(at -21.20011 -2.22504 270)
			(size 0.508 2.0574)
			(layers "F.Cu" "F.Mask" "F.Paste")
			(net "GND")
		)
		(pad "58" smd rect
			(at -21.999956 -2.22504 270)
			(size 0.508 2.0574)
			(layers "F.Cu" "F.Mask" "F.Paste")
			(net "Net_1330")
		)
		(pad "59" smd rect
			(at -22.800056 -2.22504 270)
			(size 0.508 2.0574)
			(layers "F.Cu" "F.Mask" "F.Paste")
			(net "Net_1329")
		)
		(pad "60" smd rect
			(at -23.599902 -2.22504 270)
			(size 0.508 2.0574)
			(layers "F.Cu" "F.Mask" "F.Paste")
			(net "GND")
		)
		(pad "61" smd rect
			(at 23.599902 2.22504 270)
			(size 0.508 2.0574)
			(layers "F.Cu" "F.Mask" "F.Paste")
			(net "P12V")
		)
		(pad "62" smd rect
			(at 22.800056 2.22504 270)
			(size 0.508 2.0574)
			(layers "F.Cu" "F.Mask" "F.Paste")
			(net "P12V")
		)
		(pad "63" smd rect
			(at 21.999956 2.22504 270)
			(size 0.508 2.0574)
			(layers "F.Cu" "F.Mask" "F.Paste")
			(net "P12V")
		)
		(pad "64" smd rect
			(at 21.20011 2.22504 270)
			(size 0.508 2.0574)
			(layers "F.Cu" "F.Mask" "F.Paste")
			(net "GND")
		)
		(pad "65" smd rect
			(at 20.40001 2.22504 270)
			(size 0.508 2.0574)
			(layers "F.Cu" "F.Mask" "F.Paste")
			(net "GND")
		)
		(pad "66" smd rect
			(at 19.59991 2.22504 270)
			(size 0.508 2.0574)
			(layers "F.Cu" "F.Mask" "F.Paste")
			(net "P3V3_STBY")
		)
		(pad "67" smd rect
			(at 18.800064 2.22504 270)
			(size 0.508 2.0574)
			(layers "F.Cu" "F.Mask" "F.Paste")
			(net "GND")
		)
		(pad "68" smd rect
			(at 17.999964 2.22504 270)
			(size 0.508 2.0574)
			(layers "F.Cu" "F.Mask" "F.Paste")
			(net "GND")
		)
		(pad "69" smd rect
			(at 17.200118 2.22504 270)
			(size 0.508 2.0574)
			(layers "F.Cu" "F.Mask" "F.Paste")
			(net "P3V3")
		)
		(pad "70" smd rect
			(at 16.400018 2.22504 270)
			(size 0.508 2.0574)
			(layers "F.Cu" "F.Mask" "F.Paste")
			(net "P3V3")
		)
		(pad "71" smd rect
			(at 15.599918 2.22504 270)
			(size 0.508 2.0574)
			(layers "F.Cu" "F.Mask" "F.Paste")
			(net "P3V3")
		)
		(pad "72" smd rect
			(at 14.800072 2.22504 270)
			(size 0.508 2.0574)
			(layers "F.Cu" "F.Mask" "F.Paste")
			(net "P3V3")
		)
		(pad "73" smd rect
			(at 13.999972 2.22504 270)
			(size 0.508 2.0574)
			(layers "F.Cu" "F.Mask" "F.Paste")
			(net "GND")
		)
		(pad "74" smd rect
			(at 13.200126 2.22504 270)
			(size 0.508 2.0574)
			(layers "F.Cu" "F.Mask" "F.Paste")
			(net "SMB_LAN_ALERT_N")
		)
		(pad "75" smd rect
			(at 12.400026 2.22504 270)
			(size 0.508 2.0574)
			(layers "F.Cu" "F.Mask" "F.Paste")
			(net "SAS_I2C_C_10G_SCL")
		)
		(pad "76" smd rect
			(at 11.599926 2.22504 270)
			(size 0.508 2.0574)
			(layers "F.Cu" "F.Mask" "F.Paste")
			(net "SAS_I2C_C_10G_SDA")
		)
		(pad "77" smd rect
			(at 10.80008 2.22504 270)
			(size 0.508 2.0574)
			(layers "F.Cu" "F.Mask" "F.Paste")
			(net "PMU_WAKE_N_R")
		)
		(pad "78" smd rect
			(at 9.99998 2.22504 270)
			(size 0.508 2.0574)
			(layers "F.Cu" "F.Mask" "F.Paste")
			(net "NCSI_10G_RX_ER_R")
		)
		(pad "79" smd rect
			(at 9.19988 2.22504 270)
			(size 0.508 2.0574)
			(layers "F.Cu" "F.Mask" "F.Paste")
			(net "GND")
		)
		(pad "80" smd rect
			(at 8.400034 2.22504 270)
			(size 0.508 2.0574)
			(layers "F.Cu" "F.Mask" "F.Paste")
			(net "NCSI_10G_TXD0_R")
		)
		(pad "81" smd rect
			(at 7.599934 2.22504 270)
			(size 0.508 2.0574)
			(layers "F.Cu" "F.Mask" "F.Paste")
			(net "NCSI_10G_TXD1_R")
		)
		(pad "82" smd rect
			(at 6.800088 2.22504 270)
			(size 0.508 2.0574)
			(layers "F.Cu" "F.Mask" "F.Paste")
			(net "GND")
		)
		(pad "83" smd rect
			(at 5.999988 2.22504 270)
			(size 0.508 2.0574)
			(layers "F.Cu" "F.Mask" "F.Paste")
			(net "GND")
		)
		(pad "84" smd rect
			(at 5.199888 2.22504 270)
			(size 0.508 2.0574)
			(layers "F.Cu" "F.Mask" "F.Paste")
			(net "PCIE_10G_REFCLK_P")
		)
		(pad "85" smd rect
			(at 4.400042 2.22504 270)
			(size 0.508 2.0574)
			(layers "F.Cu" "F.Mask" "F.Paste")
			(net "PCIE_10G_REFCLK_N")
		)
		(pad "86" smd rect
			(at 3.599942 2.22504 270)
			(size 0.508 2.0574)
			(layers "F.Cu" "F.Mask" "F.Paste")
			(net "GND")
		)
		(pad "87" smd rect
			(at 2.800096 2.22504 270)
			(size 0.508 2.0574)
			(layers "F.Cu" "F.Mask" "F.Paste")
			(net "GND")
		)
		(pad "88" smd rect
			(at 1.999996 2.22504 270)
			(size 0.508 2.0574)
			(layers "F.Cu" "F.Mask" "F.Paste")
			(net "PCIE_10G_CPU_TX0_P")
		)
		(pad "89" smd rect
			(at 1.199896 2.22504 270)
			(size 0.508 2.0574)
			(layers "F.Cu" "F.Mask" "F.Paste")
			(net "PCIE_10G_CPU_TX0_N")
		)
		(pad "90" smd rect
			(at 0.40005 2.22504 270)
			(size 0.508 2.0574)
			(layers "F.Cu" "F.Mask" "F.Paste")
			(net "GND")
		)
		(pad "91" smd rect
			(at -0.40005 2.22504 270)
			(size 0.508 2.0574)
			(layers "F.Cu" "F.Mask" "F.Paste")
			(net "GND")
		)
		(pad "92" smd rect
			(at -1.199896 2.22504 270)
			(size 0.508 2.0574)
			(layers "F.Cu" "F.Mask" "F.Paste")
			(net "PCIE_10G_CPU_TX1_P")
		)
		(pad "93" smd rect
			(at -1.999996 2.22504 270)
			(size 0.508 2.0574)
			(layers "F.Cu" "F.Mask" "F.Paste")
			(net "PCIE_10G_CPU_TX1_N")
		)
		(pad "94" smd rect
			(at -2.800096 2.22504 270)
			(size 0.508 2.0574)
			(layers "F.Cu" "F.Mask" "F.Paste")
			(net "GND")
		)
		(pad "95" smd rect
			(at -3.599942 2.22504 270)
			(size 0.508 2.0574)
			(layers "F.Cu" "F.Mask" "F.Paste")
			(net "GND")
		)
		(pad "96" smd rect
			(at -4.400042 2.22504 270)
			(size 0.508 2.0574)
			(layers "F.Cu" "F.Mask" "F.Paste")
			(net "PCIE_10G_CPU_TX2_P")
		)
		(pad "97" smd rect
			(at -5.199888 2.22504 270)
			(size 0.508 2.0574)
			(layers "F.Cu" "F.Mask" "F.Paste")
			(net "PCIE_10G_CPU_TX2_N")
		)
		(pad "98" smd rect
			(at -5.999988 2.22504 270)
			(size 0.508 2.0574)
			(layers "F.Cu" "F.Mask" "F.Paste")
			(net "GND")
		)
		(pad "99" smd rect
			(at -6.800088 2.22504 270)
			(size 0.508 2.0574)
			(layers "F.Cu" "F.Mask" "F.Paste")
			(net "GND")
		)
		(pad "100" smd rect
			(at -7.599934 2.22504 270)
			(size 0.508 2.0574)
			(layers "F.Cu" "F.Mask" "F.Paste")
			(net "PCIE_10G_CPU_TX3_P")
		)
		(pad "101" smd rect
			(at -8.400034 2.22504 270)
			(size 0.508 2.0574)
			(layers "F.Cu" "F.Mask" "F.Paste")
			(net "PCIE_10G_CPU_TX3_N")
		)
		(pad "102" smd rect
			(at -9.19988 2.22504 270)
			(size 0.508 2.0574)
			(layers "F.Cu" "F.Mask" "F.Paste")
			(net "GND")
		)
		(pad "103" smd rect
			(at -9.99998 2.22504 270)
			(size 0.508 2.0574)
			(layers "F.Cu" "F.Mask" "F.Paste")
			(net "GND")
		)
		(pad "104" smd rect
			(at -10.80008 2.22504 270)
			(size 0.508 2.0574)
			(layers "F.Cu" "F.Mask" "F.Paste")
			(net "Net_1316")
		)
		(pad "105" smd rect
			(at -11.599926 2.22504 270)
			(size 0.508 2.0574)
			(layers "F.Cu" "F.Mask" "F.Paste")
			(net "Net_1321")
		)
		(pad "106" smd rect
			(at -12.400026 2.22504 270)
			(size 0.508 2.0574)
			(layers "F.Cu" "F.Mask" "F.Paste")
			(net "GND")
		)
		(pad "107" smd rect
			(at -13.200126 2.22504 270)
			(size 0.508 2.0574)
			(layers "F.Cu" "F.Mask" "F.Paste")
			(net "GND")
		)
		(pad "108" smd rect
			(at -13.999972 2.22504 270)
			(size 0.508 2.0574)
			(layers "F.Cu" "F.Mask" "F.Paste")
			(net "Net_1320")
		)
		(pad "109" smd rect
			(at -14.800072 2.22504 270)
			(size 0.508 2.0574)
			(layers "F.Cu" "F.Mask" "F.Paste")
			(net "Net_1319")
		)
		(pad "110" smd rect
			(at -15.599918 2.22504 270)
			(size 0.508 2.0574)
			(layers "F.Cu" "F.Mask" "F.Paste")
			(net "GND")
		)
		(pad "111" smd rect
			(at -16.400018 2.22504 270)
			(size 0.508 2.0574)
			(layers "F.Cu" "F.Mask" "F.Paste")
			(net "GND")
		)
		(pad "112" smd rect
			(at -17.200118 2.22504 270)
			(size 0.508 2.0574)
			(layers "F.Cu" "F.Mask" "F.Paste")
			(net "Net_1318")
		)
		(pad "113" smd rect
			(at -17.999964 2.22504 270)
			(size 0.508 2.0574)
			(layers "F.Cu" "F.Mask" "F.Paste")
			(net "Net_1317")
		)
		(pad "114" smd rect
			(at -18.800064 2.22504 270)
			(size 0.508 2.0574)
			(layers "F.Cu" "F.Mask" "F.Paste")
			(net "GND")
		)
		(pad "115" smd rect
			(at -19.59991 2.22504 270)
			(size 0.508 2.0574)
			(layers "F.Cu" "F.Mask" "F.Paste")
			(net "GND")
		)
		(pad "116" smd rect
			(at -20.40001 2.22504 270)
			(size 0.508 2.0574)
			(layers "F.Cu" "F.Mask" "F.Paste")
			(net "Net_1328")
		)
		(pad "117" smd rect
			(at -21.20011 2.22504 270)
			(size 0.508 2.0574)
			(layers "F.Cu" "F.Mask" "F.Paste")
			(net "Net_1327")
		)
		(pad "118" smd rect
			(at -21.999956 2.22504 270)
			(size 0.508 2.0574)
			(layers "F.Cu" "F.Mask" "F.Paste")
			(net "GND")
		)
	)
)
